(kicad_pcb
	(version 20260206)
	(generator "pcbnew")
	(generator_version "10.0")
	(general
		(thickness 1.6)
		(legacy_teardrops no)
	)
	(paper "A4")
	(title_block
		(title "Wiwynn_Tioga_Pass_MB.brd")
		(comment 1 "Tioga Pass / footprints 1011-1017 of 4770")
	)
	(layers
		(0 "F.Cu" signal "TOP")
		(4 "In1.Cu" signal "L2GND")
		(6 "In2.Cu" signal "L3")
		(8 "In3.Cu" signal "L4GND")
		(10 "In4.Cu" signal "L5")
		(12 "In5.Cu" signal "L6GND")
		(14 "In6.Cu" signal "L7VCC")
		(16 "In7.Cu" signal "L8VCC")
		(18 "In8.Cu" signal "L9GND")
		(20 "In9.Cu" signal "L10")
		(22 "In10.Cu" signal "L11GND")
		(24 "In11.Cu" signal "L12")
		(26 "In12.Cu" signal "L13GND")
		(2 "B.Cu" signal "BOTTOM")
		(9 "F.Adhes" user "F.Adhesive")
		(11 "B.Adhes" user "B.Adhesive")
		(13 "F.Paste" user "Package Geometry/Pastemask Top")
		(15 "B.Paste" user "Package Geometry/Pastemask Bottom")
		(5 "F.SilkS" user "Ref Des/Silkscreen Top")
		(7 "B.SilkS" user "Ref Des/Silkscreen Bottom")
		(1 "F.Mask" user "Board Geometry/Soldermask Top")
		(3 "B.Mask" user "Board Geometry/Soldermask Bottom")
		(17 "Dwgs.User" user "User.Drawings")
		(19 "Cmts.User" user "User.Comments")
		(21 "Eco1.User" user "User.Eco1")
		(23 "Eco2.User" user "User.Eco2")
		(25 "Edge.Cuts" user "Board Geometry/Outline")
		(27 "Margin" user)
		(31 "F.CrtYd" user "Package Geometry/Place Bound Top")
		(29 "B.CrtYd" user "Package Geometry/Place Bound Bottom")
		(35 "F.Fab" user "Ref Des/Assembly Top")
		(33 "B.Fab" user "Ref Des/Assembly Bottom")
	)
	(footprint ""
		(layer "F.Cu")
		(at 184.421272 -9.119108 90)
		(property "Reference" "C4G5"
			(at 0 0 90)
			(layer "F.SilkS")
			(hide yes)
			(effects
				(font
					(size 1.27 1.27)
				)
			)
		)
		(property "Value" "*"
			(at -0.0762 -6.2357 90)
			(unlocked yes)
			(layer "F.Fab")
			(hide yes)
			(effects
				(font
					(size 1.27 1.016)
					(thickness 0.1524)
				)
			)
		)
		(property "Device Type" "SC22U16V5MX-4-GP_SMD-BCG5-SC22A"
			(at -0.0762 -8.2677 90)
			(unlocked yes)
			(layer "F.Fab")
			(hide yes)
			(effects
				(font
					(size 1.27 1.016)
					(thickness 0.1524)
				)
			)
		)
		(duplicate_pad_numbers_are_jumpers no)
		(fp_line
			(start 0.635 0)
			(end -0.635 0)
			(stroke
				(width 0.508)
				(type default)
			)
			(layer "F.SilkS")
		)
		(fp_rect
			(start -0.9652 1.778)
			(end 0.9652 -1.778)
			(stroke
				(width 0)
				(type default)
			)
			(fill no)
			(layer "F.CrtYd")
		)
		(fp_poly
			(pts
				(xy -0.9652 -1.778) (xy 0.9652 -1.778) (xy 0.9652 1.778) (xy -0.9652 1.778)
			)
			(stroke
				(width 0)
				(type default)
			)
			(fill no)
			(layer "F.Fab")
		)
		(pad "1" smd rect
			(at 0 -0.9652 90)
			(size 1.397 1.143)
			(layers "F.Cu" "F.Mask" "F.Paste")
			(net "VR_FET_SW_P12V_STBY_PVPP_GHJ")
		)
		(pad "2" smd rect
			(at 0 0.9652 90)
			(size 1.397 1.143)
			(layers "F.Cu" "F.Mask" "F.Paste")
			(net "GND")
		)
	)
	(footprint ""
		(layer "F.Cu")
		(at 408.520392 -10.916666)
		(property "Reference" "C8G8"
			(at 0 0 0)
			(layer "F.SilkS")
			(hide yes)
			(effects
				(font
					(size 1.27 1.27)
				)
			)
		)
		(property "Value" ""
			(at 0 0 0)
			(layer "F.Fab")
			(effects
				(font
					(size 1.27 1.27)
				)
			)
		)
		(duplicate_pad_numbers_are_jumpers no)
		(fp_rect
			(start -0.3048 0.9906)
			(end 0.3048 -0.1016)
			(stroke
				(width 0)
				(type default)
			)
			(fill no)
			(layer "F.CrtYd")
		)
		(fp_line
			(start -0.3048 -0.1016)
			(end -0.3048 0.9906)
			(stroke
				(width 0.1)
				(type default)
			)
			(layer "F.Fab")
		)
		(fp_line
			(start -0.3048 0.9906)
			(end 0.3048 0.9906)
			(stroke
				(width 0.1)
				(type default)
			)
			(layer "F.Fab")
		)
		(fp_line
			(start 0.3048 -0.1016)
			(end -0.3048 -0.1016)
			(stroke
				(width 0.1)
				(type default)
			)
			(layer "F.Fab")
		)
		(fp_line
			(start 0.3048 0.9906)
			(end 0.3048 -0.1016)
			(stroke
				(width 0.1)
				(type default)
			)
			(layer "F.Fab")
		)
		(pad "1" smd rect
			(at 0 0)
			(size 0.508 0.508)
			(layers "F.Cu" "F.Mask" "F.Paste")
			(net "P3E_CPU0_PE2_SS_TXP<1>")
		)
		(pad "2" smd rect
			(at 0 0.889)
			(size 0.508 0.508)
			(layers "F.Cu" "F.Mask" "F.Paste")
			(net "P3E_CPU0_PE2_SS_C_TXP<1>")
		)
		(zone
			(layer "F.Cu")
			(hatch none 0.5)
			(connect_pads
				(clearance 0)
			)
			(min_thickness 0.25)
			(keepout
				(tracks not_allowed)
				(vias allowed)
				(pads allowed)
				(copperpour not_allowed)
				(footprints allowed)
			)
			(placement
				(enabled no)
				(sheetname "")
			)
			(fill
				(thermal_gap 0.5)
				(thermal_bridge_width 0.5)
				(island_removal_mode 0)
			)
			(polygon
				(pts
					(xy 408.266392 -10.281666) (xy 408.774392 -10.281666) (xy 408.774392 -10.662666) (xy 408.266392 -10.662666)
				)
			)
		)
		(zone
			(layer "F.Cu")
			(hatch none 0.5)
			(connect_pads
				(clearance 0)
			)
			(min_thickness 0.25)
			(keepout
				(tracks allowed)
				(vias not_allowed)
				(pads allowed)
				(copperpour not_allowed)
				(footprints allowed)
			)
			(placement
				(enabled no)
				(sheetname "")
			)
			(fill
				(thermal_gap 0.5)
				(thermal_bridge_width 0.5)
				(island_removal_mode 0)
			)
			(polygon
				(pts
					(xy 408.266392 -10.281666) (xy 408.774392 -10.281666) (xy 408.774392 -10.662666) (xy 408.266392 -10.662666)
				)
			)
		)
	)
	(footprint ""
		(layer "F.Cu")
		(at 22.225 -81.788)
		(property "Reference" "R1D19"
			(at 0 0 0)
			(layer "F.SilkS")
			(hide yes)
			(effects
				(font
					(size 1.27 1.27)
				)
			)
		)
		(property "Value" ""
			(at 0 0 0)
			(layer "F.Fab")
			(effects
				(font
					(size 1.27 1.27)
				)
			)
		)
		(duplicate_pad_numbers_are_jumpers no)
		(fp_poly
			(pts
				(xy -0.2794 -0.1016) (xy 0.2794 -0.1016) (xy 0.2794 0.9906) (xy -0.2794 0.9906)
			)
			(stroke
				(width 0)
				(type default)
			)
			(fill no)
			(layer "F.CrtYd")
		)
		(fp_line
			(start -0.2794 -0.1016)
			(end -0.2794 0.9906)
			(stroke
				(width 0.1)
				(type default)
			)
			(layer "F.Fab")
		)
		(fp_line
			(start -0.2794 0.9906)
			(end 0.2794 0.9906)
			(stroke
				(width 0.1)
				(type default)
			)
			(layer "F.Fab")
		)
		(fp_line
			(start 0.2794 -0.1016)
			(end -0.2794 -0.1016)
			(stroke
				(width 0.1)
				(type default)
			)
			(layer "F.Fab")
		)
		(fp_line
			(start 0.2794 0.9906)
			(end 0.2794 -0.1016)
			(stroke
				(width 0.1)
				(type default)
			)
			(layer "F.Fab")
		)
		(pad "1" smd rect
			(at 0 0)
			(size 0.508 0.508)
			(layers "F.Cu" "F.Mask" "F.Paste")
			(net "A_HSC_HIGH")
		)
		(pad "2" smd rect
			(at 0 0.889)
			(size 0.508 0.508)
			(layers "F.Cu" "F.Mask" "F.Paste")
			(net "AGND_HSC")
		)
		(zone
			(layer "F.Cu")
			(hatch none 0.5)
			(connect_pads
				(clearance 0)
			)
			(min_thickness 0.25)
			(keepout
				(tracks allowed)
				(vias not_allowed)
				(pads allowed)
				(copperpour not_allowed)
				(footprints allowed)
			)
			(placement
				(enabled no)
				(sheetname "")
			)
			(fill
				(thermal_gap 0.5)
				(thermal_bridge_width 0.5)
				(island_removal_mode 0)
			)
			(polygon
				(pts
					(xy 21.971 -81.534) (xy 22.479 -81.534) (xy 22.479 -81.153) (xy 21.971 -81.153)
				)
			)
		)
		(zone
			(layer "F.Cu")
			(hatch none 0.5)
			(connect_pads
				(clearance 0)
			)
			(min_thickness 0.25)
			(keepout
				(tracks not_allowed)
				(vias allowed)
				(pads allowed)
				(copperpour not_allowed)
				(footprints allowed)
			)
			(placement
				(enabled no)
				(sheetname "")
			)
			(fill
				(thermal_gap 0.5)
				(thermal_bridge_width 0.5)
				(island_removal_mode 0)
			)
			(polygon
				(pts
					(xy 21.971 -81.153) (xy 22.479 -81.153) (xy 22.479 -81.534) (xy 21.971 -81.534)
				)
			)
		)
	)
	(footprint ""
		(layer "F.Cu")
		(at 410.7688 -99.3394 90)
		(property "Reference" "R2P12"
			(at 0 0 90)
			(layer "F.SilkS")
			(hide yes)
			(effects
				(font
					(size 1.27 1.27)
				)
			)
		)
		(property "Value" ""
			(at 0 0 90)
			(layer "F.Fab")
			(effects
				(font
					(size 1.27 1.27)
				)
			)
		)
		(duplicate_pad_numbers_are_jumpers no)
		(fp_poly
			(pts
				(xy -0.2794 -0.1016) (xy 0.2794 -0.1016) (xy 0.2794 0.9906) (xy -0.2794 0.9906)
			)
			(stroke
				(width 0)
				(type default)
			)
			(fill no)
			(layer "F.CrtYd")
		)
		(fp_line
			(start 0.2794 -0.1016)
			(end -0.2794 -0.1016)
			(stroke
				(width 0.1)
				(type default)
			)
			(layer "F.Fab")
		)
		(fp_line
			(start -0.2794 -0.1016)
			(end -0.2794 0.9906)
			(stroke
				(width 0.1)
				(type default)
			)
			(layer "F.Fab")
		)
		(fp_line
			(start 0.2794 0.9906)
			(end 0.2794 -0.1016)
			(stroke
				(width 0.1)
				(type default)
			)
			(layer "F.Fab")
		)
		(fp_line
			(start -0.2794 0.9906)
			(end 0.2794 0.9906)
			(stroke
				(width 0.1)
				(type default)
			)
			(layer "F.Fab")
		)
		(pad "1" smd rect
			(at 0 0 90)
			(size 0.508 0.508)
			(layers "F.Cu" "F.Mask" "F.Paste")
			(net "IRQ_DIMM_SAVE_LVT3_N")
		)
		(pad "2" smd rect
			(at 0 0.889 90)
			(size 0.508 0.508)
			(layers "F.Cu" "F.Mask" "F.Paste")
			(net "FM_ADR_SMI_GPIO_N")
		)
		(zone
			(layer "F.Cu")
			(hatch none 0.5)
			(connect_pads
				(clearance 0)
			)
			(min_thickness 0.25)
			(keepout
				(tracks allowed)
				(vias not_allowed)
				(pads allowed)
				(copperpour not_allowed)
				(footprints allowed)
			)
			(placement
				(enabled no)
				(sheetname "")
			)
			(fill
				(thermal_gap 0.5)
				(thermal_bridge_width 0.5)
				(island_removal_mode 0)
			)
			(polygon
				(pts
					(xy 411.0228 -99.0854) (xy 411.0228 -99.5934) (xy 411.4038 -99.5934) (xy 411.4038 -99.0854)
				)
			)
		)
		(zone
			(layer "F.Cu")
			(hatch none 0.5)
			(connect_pads
				(clearance 0)
			)
			(min_thickness 0.25)
			(keepout
				(tracks not_allowed)
				(vias allowed)
				(pads allowed)
				(copperpour not_allowed)
				(footprints allowed)
			)
			(placement
				(enabled no)
				(sheetname "")
			)
			(fill
				(thermal_gap 0.5)
				(thermal_bridge_width 0.5)
				(island_removal_mode 0)
			)
			(polygon
				(pts
					(xy 411.4038 -99.0854) (xy 411.4038 -99.5934) (xy 411.0228 -99.5934) (xy 411.0228 -99.0854)
				)
			)
		)
	)
	(footprint ""
		(layer "F.Cu")
		(at 391.16 -0.254)
		(property "Reference" "R8G9"
			(at 0 0 0)
			(layer "F.SilkS")
			(hide yes)
			(effects
				(font
					(size 1.27 1.27)
				)
			)
		)
		(property "Value" ""
			(at 0 0 0)
			(layer "F.Fab")
			(effects
				(font
					(size 1.27 1.27)
				)
			)
		)
		(duplicate_pad_numbers_are_jumpers no)
		(fp_poly
			(pts
				(xy -0.2794 -0.1016) (xy 0.2794 -0.1016) (xy 0.2794 0.9906) (xy -0.2794 0.9906)
			)
			(stroke
				(width 0)
				(type default)
			)
			(fill no)
			(layer "F.CrtYd")
		)
		(fp_line
			(start -0.2794 -0.1016)
			(end -0.2794 0.9906)
			(stroke
				(width 0.1)
				(type default)
			)
			(layer "F.Fab")
		)
		(fp_line
			(start -0.2794 0.9906)
			(end 0.2794 0.9906)
			(stroke
				(width 0.1)
				(type default)
			)
			(layer "F.Fab")
		)
		(fp_line
			(start 0.2794 -0.1016)
			(end -0.2794 -0.1016)
			(stroke
				(width 0.1)
				(type default)
			)
			(layer "F.Fab")
		)
		(fp_line
			(start 0.2794 0.9906)
			(end 0.2794 -0.1016)
			(stroke
				(width 0.1)
				(type default)
			)
			(layer "F.Fab")
		)
		(pad "1" smd rect
			(at 0 0)
			(size 0.508 0.508)
			(layers "F.Cu" "F.Mask" "F.Paste")
			(net "JTAG_PCH_GBE_TRST_N")
		)
		(pad "2" smd rect
			(at 0 0.889)
			(size 0.508 0.508)
			(layers "F.Cu" "F.Mask" "F.Paste")
			(net "JTAG_TRST_N")
		)
		(zone
			(layer "F.Cu")
			(hatch none 0.5)
			(connect_pads
				(clearance 0)
			)
			(min_thickness 0.25)
			(keepout
				(tracks allowed)
				(vias not_allowed)
				(pads allowed)
				(copperpour not_allowed)
				(footprints allowed)
			)
			(placement
				(enabled no)
				(sheetname "")
			)
			(fill
				(thermal_gap 0.5)
				(thermal_bridge_width 0.5)
				(island_removal_mode 0)
			)
			(polygon
				(pts
					(xy 390.906 0) (xy 391.414 0) (xy 391.414 0.381) (xy 390.906 0.381)
				)
			)
		)
		(zone
			(layer "F.Cu")
			(hatch none 0.5)
			(connect_pads
				(clearance 0)
			)
			(min_thickness 0.25)
			(keepout
				(tracks not_allowed)
				(vias allowed)
				(pads allowed)
				(copperpour not_allowed)
				(footprints allowed)
			)
			(placement
				(enabled no)
				(sheetname "")
			)
			(fill
				(thermal_gap 0.5)
				(thermal_bridge_width 0.5)
				(island_removal_mode 0)
			)
			(polygon
				(pts
					(xy 390.906 0.381) (xy 391.414 0.381) (xy 391.414 0) (xy 390.906 0)
				)
			)
		)
	)
	(footprint ""
		(layer "F.Cu")
		(at 195.58 -3.321812 90)
		(property "Reference" "C4G19"
			(at 0 0 90)
			(layer "F.SilkS")
			(hide yes)
			(effects
				(font
					(size 1.27 1.27)
				)
			)
		)
		(property "Value" ""
			(at 0 0 90)
			(layer "F.Fab")
			(effects
				(font
					(size 1.27 1.27)
				)
			)
		)
		(duplicate_pad_numbers_are_jumpers no)
		(fp_poly
			(pts
				(xy 0.3048 -0.1016) (xy 0.3048 0.9906) (xy -0.3048 0.9906) (xy -0.3048 -0.1016)
			)
			(stroke
				(width 0)
				(type default)
			)
			(fill no)
			(layer "F.CrtYd")
		)
		(fp_line
			(start 0.3048 -0.1016)
			(end -0.3048 -0.1016)
			(stroke
				(width 0.1)
				(type default)
			)
			(layer "F.Fab")
		)
		(fp_line
			(start -0.3048 -0.1016)
			(end -0.3048 0.9906)
			(stroke
				(width 0.1)
				(type default)
			)
			(layer "F.Fab")
		)
		(fp_line
			(start 0.3048 0.9906)
			(end 0.3048 -0.1016)
			(stroke
				(width 0.1)
				(type default)
			)
			(layer "F.Fab")
		)
		(fp_line
			(start -0.3048 0.9906)
			(end 0.3048 0.9906)
			(stroke
				(width 0.1)
				(type default)
			)
			(layer "F.Fab")
		)
		(pad "1" smd rect
			(at 0 0 90)
			(size 0.508 0.508)
			(layers "F.Cu" "F.Mask" "F.Paste")
			(net "M_C_VREF")
		)
		(pad "2" smd rect
			(at 0 0.889 90)
			(size 0.508 0.508)
			(layers "F.Cu" "F.Mask" "F.Paste")
			(net "GND")
		)
		(zone
			(layer "F.Cu")
			(hatch none 0.5)
			(connect_pads
				(clearance 0)
			)
			(min_thickness 0.25)
			(keepout
				(tracks allowed)
				(vias not_allowed)
				(pads allowed)
				(copperpour not_allowed)
				(footprints allowed)
			)
			(placement
				(enabled no)
				(sheetname "")
			)
			(fill
				(thermal_gap 0.5)
				(thermal_bridge_width 0.5)
				(island_removal_mode 0)
			)
			(polygon
				(pts
					(xy 195.834 -3.067812) (xy 195.834 -3.575812) (xy 196.215 -3.575812) (xy 196.215 -3.067812)
				)
			)
		)
		(zone
			(layer "F.Cu")
			(hatch none 0.5)
			(connect_pads
				(clearance 0)
			)
			(min_thickness 0.25)
			(keepout
				(tracks not_allowed)
				(vias allowed)
				(pads allowed)
				(copperpour not_allowed)
				(footprints allowed)
			)
			(placement
				(enabled no)
				(sheetname "")
			)
			(fill
				(thermal_gap 0.5)
				(thermal_bridge_width 0.5)
				(island_removal_mode 0)
			)
			(polygon
				(pts
					(xy 196.215 -3.067812) (xy 196.215 -3.575812) (xy 195.834 -3.575812) (xy 195.834 -3.067812)
				)
			)
		)
	)
	(footprint ""
		(layer "F.Cu")
		(at 229.23881 -164.911786 90)
		(property "Reference" "T1D14"
			(at 0 0 90)
			(layer "F.SilkS")
			(hide yes)
			(effects
				(font
					(size 1.27 1.27)
				)
			)
		)
		(property "Value" "*"
			(at -3.4036 -4.46405 90)
			(unlocked yes)
			(layer "F.Fab")
			(hide yes)
			(effects
				(font
					(size 0.889 0.889)
					(thickness 0.1524)
				)
			)
		)
		(property "Device Type" "TEST-PAD-12P-1-GP-U_DISCRET-GBA"
			(at -3.4036 -5.98805 90)
			(unlocked yes)
			(layer "F.Fab")
			(hide yes)
			(effects
				(font
					(size 0.889 0.889)
					(thickness 0.1524)
				)
			)
		)
		(duplicate_pad_numbers_are_jumpers no)
		(fp_line
			(start 2.3622 -4.826)
			(end 2.3622 3.4798)
			(stroke
				(width 0.1524)
				(type default)
			)
			(layer "F.SilkS")
		)
		(fp_line
			(start -2.3876 -4.826)
			(end 2.3622 -4.826)
			(stroke
				(width 0.1524)
				(type default)
			)
			(layer "F.SilkS")
		)
		(fp_line
			(start 2.3622 3.4798)
			(end -2.3876 3.4798)
			(stroke
				(width 0.1524)
				(type default)
			)
			(layer "F.SilkS")
		)
		(fp_line
			(start -2.3876 3.4798)
			(end -2.3876 -4.826)
			(stroke
				(width 0.1524)
				(type default)
			)
			(layer "F.SilkS")
		)
		(fp_rect
			(start -2.6416 3.7338)
			(end 2.6162 -5.08)
			(stroke
				(width 0)
				(type default)
			)
			(fill no)
			(layer "F.CrtYd")
		)
		(fp_rect
			(start -2.6416 3.7338)
			(end 2.6162 -5.08)
			(stroke
				(width 0)
				(type default)
			)
			(fill no)
			(layer "F.Fab")
		)
		(pad "1" smd circle
			(at 0.496824 -1.301496 90)
			(size 0.6604 0.6604)
			(layers "F.Cu" "F.Mask" "F.Paste")
			(net "L1_85OHM_10INCH_DN")
		)
		(pad "2" smd circle
			(at -0.503936 -1.301496 90)
			(size 0.6604 0.6604)
			(layers "F.Cu" "F.Mask" "F.Paste")
			(net "L1_85OHM_10INCH_DP")
		)
		(pad "3" smd custom
			(at -0.00889 0.370078 90)
			(size 0.74295 0.74295)
			(layers "F.Cu" "F.Mask" "F.Paste")
			(net "GND")
			(options
				(clearance outline)
				(anchor circle)
			)
			(primitives
				(gr_poly
					(pts
						(xy -2.1209 1.4859) (xy 2.1209 1.4859) (xy 2.1209 -1.4859) (xy 1.08585 -1.4859) (xy 1.08585 -0.4699)
						(xy -1.08585 -0.4699) (xy -1.08585 -1.4859) (xy -2.1209 -1.4859)
					)
					(width 0)
					(fill yes)
				)
			)
		)
		(pad "4" thru_hole circle
			(at 1.266444 -3.851656 90)
			(size 1.4478 1.4478)
			(drill 1.0414)
			(layers "*.Cu" "*.Mask")
			(remove_unused_layers no)
			(net "GND")
			(clearance 0.1524)
			(thermal_gap 0.1524)
		)
		(pad "5" thru_hole circle
			(at -1.273556 -3.851656 90)
			(size 1.4478 1.4478)
			(drill 1.0414)
			(layers "*.Cu" "*.Mask")
			(remove_unused_layers no)
			(net "GND")
			(clearance 0.1524)
			(thermal_gap 0.1524)
		)
		(pad "6" thru_hole circle
			(at 1.266444 2.498344 90)
			(size 1.4478 1.4478)
			(drill 1.0414)
			(layers "*.Cu" "*.Mask")
			(remove_unused_layers no)
			(net "GND")
			(clearance 0.1524)
			(thermal_gap 0.1524)
		)
		(pad "7" thru_hole circle
			(at -1.273556 2.498344 90)
			(size 1.4478 1.4478)
			(drill 1.0414)
			(layers "*.Cu" "*.Mask")
			(remove_unused_layers no)
			(net "GND")
			(clearance 0.1524)
			(thermal_gap 0.1524)
		)
		(pad "8" thru_hole circle
			(at 1.27 -0.4572 90)
			(size 0.7112 0.7112)
			(drill 0.4064)
			(layers "*.Cu" "*.Mask")
			(remove_unused_layers no)
			(net "GND")
			(clearance 0.1016)
			(thermal_gap 0.1016)
		)
		(pad "9" thru_hole circle
			(at 1.27 0.762 90)
			(size 0.7112 0.7112)
			(drill 0.4064)
			(layers "*.Cu" "*.Mask")
			(remove_unused_layers no)
			(net "GND")
			(clearance 0.1016)
			(thermal_gap 0.1016)
		)
		(pad "10" thru_hole circle
			(at -0.0254 0.762 90)
			(size 0.7112 0.7112)
			(drill 0.4064)
			(layers "*.Cu" "*.Mask")
			(remove_unused_layers no)
			(net "GND")
			(clearance 0.1016)
			(thermal_gap 0.1016)
		)
		(pad "11" thru_hole circle
			(at -1.27 0.762 90)
			(size 0.7112 0.7112)
			(drill 0.4064)
			(layers "*.Cu" "*.Mask")
			(remove_unused_layers no)
			(net "GND")
			(clearance 0.1016)
			(thermal_gap 0.1016)
		)
		(pad "12" thru_hole circle
			(at -1.27 -0.4572 90)
			(size 0.7112 0.7112)
			(drill 0.4064)
			(layers "*.Cu" "*.Mask")
			(remove_unused_layers no)
			(net "GND")
			(clearance 0.1016)
			(thermal_gap 0.1016)
		)
	)
)
